(kicad_pcb
	(version 20260206)
	(generator "pcbnew")
	(generator_version "10.0")
	(general
		(thickness 1.6)
		(legacy_teardrops no)
	)
	(paper "A4")
	(title_block
		(title "Bryce Canyon_R.DPB_16317-1_OCP.brd")
		(comment 1 "Bryce Canyon / footprints 1314-1318 of 2099")
	)
	(layers
		(0 "F.Cu" signal "TOP")
		(4 "In1.Cu" signal "L2GND")
		(6 "In2.Cu" signal "L3")
		(8 "In3.Cu" signal "L4VCC")
		(10 "In4.Cu" signal "L5VCC")
		(12 "In5.Cu" signal "L6")
		(14 "In6.Cu" signal "L7GND")
		(2 "B.Cu" signal "BOTTOM")
		(9 "F.Adhes" user "F.Adhesive")
		(11 "B.Adhes" user "B.Adhesive")
		(13 "F.Paste" user "Package Geometry/Pastemask Top")
		(15 "B.Paste" user "Package Geometry/Pastemask Bottom")
		(5 "F.SilkS" user "Ref Des/Silkscreen Top")
		(7 "B.SilkS" user "Ref Des/Silkscreen Bottom")
		(1 "F.Mask" user "Board Geometry/Soldermask Top")
		(3 "B.Mask" user "Board Geometry/Soldermask Bottom")
		(17 "Dwgs.User" user "User.Drawings")
		(19 "Cmts.User" user "User.Comments")
		(21 "Eco1.User" user "User.Eco1")
		(23 "Eco2.User" user "User.Eco2")
		(25 "Edge.Cuts" user "Board Geometry/Outline")
		(27 "Margin" user)
		(31 "F.CrtYd" user "Package Geometry/Place Bound Top")
		(29 "B.CrtYd" user "Package Geometry/Place Bound Bottom")
		(35 "F.Fab" user "Ref Des/Assembly Top")
		(33 "B.Fab" user "Ref Des/Assembly Bottom")
	)
	(footprint ""
		(layer "F.Cu")
		(at 22.987 -247.015 -90)
		(property "Reference" "R906"
			(at 0 0 270)
			(layer "F.SilkS")
			(hide yes)
			(effects
				(font
					(size 1.27 1.27)
				)
			)
		)
		(property "Value" "1KR2F-3-GP"
			(at 0.064008 -3.993896 270)
			(unlocked yes)
			(layer "F.Fab")
			(hide yes)
			(effects
				(font
					(size 1.016 1.016)
					(thickness 0.1524)
				)
			)
		)
		(property "Device Type" "R402H16"
			(at 0.064008 -5.517896 270)
			(unlocked yes)
			(layer "F.Fab")
			(hide yes)
			(effects
				(font
					(size 1.016 1.016)
					(thickness 0.1524)
				)
			)
		)
		(duplicate_pad_numbers_are_jumpers no)
		(fp_line
			(start -0.508 -0.9398)
			(end -0.508 0.9398)
			(stroke
				(width 0.1524)
				(type default)
			)
			(layer "F.SilkS")
		)
		(fp_line
			(start 0.508 -0.9398)
			(end -0.508 -0.9398)
			(stroke
				(width 0.1524)
				(type default)
			)
			(layer "F.SilkS")
		)
		(fp_rect
			(start -0.508 0.9398)
			(end 0.508 -0.9398)
			(stroke
				(width 0)
				(type default)
			)
			(fill no)
			(layer "F.CrtYd")
		)
		(fp_rect
			(start -0.508 0.9398)
			(end 0.508 -0.9398)
			(stroke
				(width 0)
				(type default)
			)
			(fill no)
			(layer "F.Fab")
		)
		(pad "1" smd custom
			(at 0 -0.4445 270)
			(size 0.1397 0.1397)
			(layers "F.Cu" "F.Mask" "F.Paste")
			(net "P3V3_STBY_B")
			(options
				(clearance outline)
				(anchor circle)
			)
			(primitives
				(gr_poly
					(pts
						(arc
							(start -0.1778 -0.2794)
							(mid -0.249642 -0.249642)
							(end -0.2794 -0.1778)
						)
						(arc
							(start -0.2794 0.1778)
							(mid -0.249642 0.249642)
							(end -0.1778 0.2794)
						)
						(arc
							(start 0.1778 0.2794)
							(mid 0.249642 0.249642)
							(end 0.2794 0.1778)
						)
						(arc
							(start 0.2794 -0.1778)
							(mid 0.249642 -0.249642)
							(end 0.1778 -0.2794)
						)
					)
					(width 0)
					(fill yes)
				)
			)
		)
		(pad "2" smd custom
			(at 0 0.4445 270)
			(size 0.1397 0.1397)
			(layers "F.Cu" "F.Mask" "F.Paste")
			(net "SW_PWR_R_HDD0")
			(options
				(clearance outline)
				(anchor circle)
			)
			(primitives
				(gr_poly
					(pts
						(arc
							(start -0.1778 -0.2794)
							(mid -0.249642 -0.249642)
							(end -0.2794 -0.1778)
						)
						(arc
							(start -0.2794 0.1778)
							(mid -0.249642 0.249642)
							(end -0.1778 0.2794)
						)
						(arc
							(start 0.1778 0.2794)
							(mid 0.249642 0.249642)
							(end 0.2794 0.1778)
						)
						(arc
							(start 0.2794 -0.1778)
							(mid 0.249642 -0.249642)
							(end 0.1778 -0.2794)
						)
					)
					(width 0)
					(fill yes)
				)
			)
		)
	)
	(footprint ""
		(layer "F.Cu")
		(at 363.601 -246.253 -90)
		(property "Reference" "Q27"
			(at 0 0 270)
			(layer "F.SilkS")
			(hide yes)
			(effects
				(font
					(size 1.27 1.27)
				)
			)
		)
		(property "Value" "2N7002KDW-GP"
			(at -2.3622 -8.2042 270)
			(unlocked yes)
			(layer "F.Fab")
			(hide yes)
			(effects
				(font
					(size 1.016 1.016)
					(thickness 0.1524)
				)
			)
		)
		(property "Device Type" "SOT-363H44"
			(at -2.3622 -10.1092 270)
			(unlocked yes)
			(layer "F.Fab")
			(hide yes)
			(effects
				(font
					(size 1.016 1.016)
					(thickness 0.1524)
				)
			)
		)
		(duplicate_pad_numbers_are_jumpers no)
		(fp_line
			(start -1.4478 1.7018)
			(end 1.4478 1.7018)
			(stroke
				(width 0.1524)
				(type default)
			)
			(layer "F.SilkS")
		)
		(fp_line
			(start 1.4478 1.7018)
			(end 1.4478 -1.7018)
			(stroke
				(width 0.1524)
				(type default)
			)
			(layer "F.SilkS")
		)
		(fp_line
			(start -1.27 1.524)
			(end -1.27 0.6604)
			(stroke
				(width 0.4826)
				(type default)
			)
			(layer "F.SilkS")
		)
		(fp_line
			(start -1.4478 -1.7018)
			(end -1.4478 1.7018)
			(stroke
				(width 0.1524)
				(type default)
			)
			(layer "F.SilkS")
		)
		(fp_line
			(start 1.4478 -1.7018)
			(end -1.4478 -1.7018)
			(stroke
				(width 0.1524)
				(type default)
			)
			(layer "F.SilkS")
		)
		(fp_poly
			(pts
				(xy -1.524 -1.778) (xy 1.524 -1.778) (xy 1.524 1.778) (xy -1.524 1.778)
			)
			(stroke
				(width 0)
				(type default)
			)
			(fill no)
			(layer "F.CrtYd")
		)
		(fp_poly
			(pts
				(xy -1.524 -1.778) (xy 1.524 -1.778) (xy 1.524 1.778) (xy -1.524 1.778)
			)
			(stroke
				(width 0)
				(type default)
			)
			(fill no)
			(layer "F.Fab")
		)
		(pad "1" smd rect
			(at -0.65024 0.9398 270)
			(size 0.4064 1.016)
			(layers "F.Cu" "F.Mask" "F.Paste")
			(net "GND")
		)
		(pad "2" smd rect
			(at 0 0.9398 270)
			(size 0.4064 1.016)
			(layers "F.Cu" "F.Mask" "F.Paste")
			(net "SW_PWR_R_HDD7")
		)
		(pad "3" smd rect
			(at 0.65024 0.9398 270)
			(size 0.4064 1.016)
			(layers "F.Cu" "F.Mask" "F.Paste")
			(net "SW_HDD_P7")
		)
		(pad "4" smd rect
			(at 0.65024 -0.9398 270)
			(size 0.4064 1.016)
			(layers "F.Cu" "F.Mask" "F.Paste")
			(net "GND")
		)
		(pad "5" smd rect
			(at 0 -0.9398 270)
			(size 0.4064 1.016)
			(layers "F.Cu" "F.Mask" "F.Paste")
			(net "SW_HDD_G7")
		)
		(pad "6" smd rect
			(at -0.65024 -0.9398 270)
			(size 0.4064 1.016)
			(layers "F.Cu" "F.Mask" "F.Paste")
			(net "SW_HDD_R7")
		)
	)
	(footprint ""
		(layer "F.Cu")
		(at 180.721 -134.493 90)
		(property "Reference" "R473"
			(at 0 0 90)
			(layer "F.SilkS")
			(hide yes)
			(effects
				(font
					(size 1.27 1.27)
				)
			)
		)
		(property "Value" "4K7R2F-GP"
			(at 0.064008 -3.993896 90)
			(unlocked yes)
			(layer "F.Fab")
			(hide yes)
			(effects
				(font
					(size 1.016 1.016)
					(thickness 0.1524)
				)
			)
		)
		(property "Device Type" "R402H16"
			(at 0.064008 -5.517896 90)
			(unlocked yes)
			(layer "F.Fab")
			(hide yes)
			(effects
				(font
					(size 1.016 1.016)
					(thickness 0.1524)
				)
			)
		)
		(duplicate_pad_numbers_are_jumpers no)
		(fp_line
			(start 0.508 -0.9398)
			(end -0.508 -0.9398)
			(stroke
				(width 0.1524)
				(type default)
			)
			(layer "F.SilkS")
		)
		(fp_line
			(start -0.508 -0.9398)
			(end -0.508 0.9398)
			(stroke
				(width 0.1524)
				(type default)
			)
			(layer "F.SilkS")
		)
		(fp_rect
			(start -0.508 0.9398)
			(end 0.508 -0.9398)
			(stroke
				(width 0)
				(type default)
			)
			(fill no)
			(layer "F.CrtYd")
		)
		(fp_rect
			(start -0.508 0.9398)
			(end 0.508 -0.9398)
			(stroke
				(width 0)
				(type default)
			)
			(fill no)
			(layer "F.Fab")
		)
		(pad "1" smd custom
			(at 0 -0.4445 90)
			(size 0.1397 0.1397)
			(layers "F.Cu" "F.Mask" "F.Paste")
			(net "SW_PWR_R_HDD17")
			(options
				(clearance outline)
				(anchor circle)
			)
			(primitives
				(gr_poly
					(pts
						(arc
							(start -0.1778 -0.2794)
							(mid -0.249642 -0.249642)
							(end -0.2794 -0.1778)
						)
						(arc
							(start -0.2794 0.1778)
							(mid -0.249642 0.249642)
							(end -0.1778 0.2794)
						)
						(arc
							(start 0.1778 0.2794)
							(mid 0.249642 0.249642)
							(end 0.2794 0.1778)
						)
						(arc
							(start 0.2794 -0.1778)
							(mid 0.249642 -0.249642)
							(end 0.1778 -0.2794)
						)
					)
					(width 0)
					(fill yes)
				)
			)
		)
		(pad "2" smd custom
			(at 0 0.4445 90)
			(size 0.1397 0.1397)
			(layers "F.Cu" "F.Mask" "F.Paste")
			(net "GND")
			(options
				(clearance outline)
				(anchor circle)
			)
			(primitives
				(gr_poly
					(pts
						(arc
							(start -0.1778 -0.2794)
							(mid -0.249642 -0.249642)
							(end -0.2794 -0.1778)
						)
						(arc
							(start -0.2794 0.1778)
							(mid -0.249642 0.249642)
							(end -0.1778 0.2794)
						)
						(arc
							(start 0.1778 0.2794)
							(mid 0.249642 0.249642)
							(end 0.2794 0.1778)
						)
						(arc
							(start 0.2794 -0.1778)
							(mid 0.249642 -0.249642)
							(end 0.1778 -0.2794)
						)
					)
					(width 0)
					(fill yes)
				)
			)
		)
	)
	(footprint ""
		(layer "F.Cu")
		(at 252.339602 -133.720078 -90)
		(property "Reference" "R418"
			(at 0 0 270)
			(layer "F.SilkS")
			(hide yes)
			(effects
				(font
					(size 1.27 1.27)
				)
			)
		)
		(property "Value" "1KR2J-1-GP"
			(at 0.064008 -3.993896 270)
			(unlocked yes)
			(layer "F.Fab")
			(hide yes)
			(effects
				(font
					(size 1.016 1.016)
					(thickness 0.1524)
				)
			)
		)
		(property "Device Type" "R402H16"
			(at 0.064008 -5.517896 270)
			(unlocked yes)
			(layer "F.Fab")
			(hide yes)
			(effects
				(font
					(size 1.016 1.016)
					(thickness 0.1524)
				)
			)
		)
		(duplicate_pad_numbers_are_jumpers no)
		(fp_line
			(start -0.508 -0.9398)
			(end -0.508 0.9398)
			(stroke
				(width 0.1524)
				(type default)
			)
			(layer "F.SilkS")
		)
		(fp_line
			(start 0.508 -0.9398)
			(end -0.508 -0.9398)
			(stroke
				(width 0.1524)
				(type default)
			)
			(layer "F.SilkS")
		)
		(fp_rect
			(start -0.508 0.9398)
			(end 0.508 -0.9398)
			(stroke
				(width 0)
				(type default)
			)
			(fill no)
			(layer "F.CrtYd")
		)
		(fp_rect
			(start -0.508 0.9398)
			(end 0.508 -0.9398)
			(stroke
				(width 0)
				(type default)
			)
			(fill no)
			(layer "F.Fab")
		)
		(pad "1" smd custom
			(at 0 -0.4445 270)
			(size 0.1397 0.1397)
			(layers "F.Cu" "F.Mask" "F.Paste")
			(net "P3V3_STBY_B")
			(options
				(clearance outline)
				(anchor circle)
			)
			(primitives
				(gr_poly
					(pts
						(arc
							(start -0.1778 -0.2794)
							(mid -0.249642 -0.249642)
							(end -0.2794 -0.1778)
						)
						(arc
							(start -0.2794 0.1778)
							(mid -0.249642 0.249642)
							(end -0.1778 0.2794)
						)
						(arc
							(start 0.1778 0.2794)
							(mid 0.249642 0.249642)
							(end 0.2794 0.1778)
						)
						(arc
							(start 0.2794 -0.1778)
							(mid 0.249642 -0.249642)
							(end 0.1778 -0.2794)
						)
					)
					(width 0)
					(fill yes)
				)
			)
		)
		(pad "2" smd custom
			(at 0 0.4445 270)
			(size 0.1397 0.1397)
			(layers "F.Cu" "F.Mask" "F.Paste")
			(net "I2C_DPB_B_SDA_BUF")
			(options
				(clearance outline)
				(anchor circle)
			)
			(primitives
				(gr_poly
					(pts
						(arc
							(start -0.1778 -0.2794)
							(mid -0.249642 -0.249642)
							(end -0.2794 -0.1778)
						)
						(arc
							(start -0.2794 0.1778)
							(mid -0.249642 0.249642)
							(end -0.1778 0.2794)
						)
						(arc
							(start 0.1778 0.2794)
							(mid 0.249642 0.249642)
							(end 0.2794 0.1778)
						)
						(arc
							(start 0.2794 -0.1778)
							(mid 0.249642 -0.249642)
							(end 0.1778 -0.2794)
						)
					)
					(width 0)
					(fill yes)
				)
			)
		)
	)
	(footprint ""
		(layer "F.Cu")
		(at 400.05 -246.761 180)
		(property "Reference" "R296"
			(at 0 0 180)
			(layer "F.SilkS")
			(hide yes)
			(effects
				(font
					(size 1.27 1.27)
				)
			)
		)
		(property "Value" "4K7R2J-2-GP"
			(at 0.064008 -3.993896 180)
			(unlocked yes)
			(layer "F.Fab")
			(hide yes)
			(effects
				(font
					(size 1.016 1.016)
					(thickness 0.1524)
				)
			)
		)
		(property "Device Type" "R402H16"
			(at 0.064008 -5.517896 180)
			(unlocked yes)
			(layer "F.Fab")
			(hide yes)
			(effects
				(font
					(size 1.016 1.016)
					(thickness 0.1524)
				)
			)
		)
		(duplicate_pad_numbers_are_jumpers no)
		(fp_line
			(start 0.508 -0.9398)
			(end -0.508 -0.9398)
			(stroke
				(width 0.1524)
				(type default)
			)
			(layer "F.SilkS")
		)
		(fp_line
			(start -0.508 -0.9398)
			(end -0.508 0.9398)
			(stroke
				(width 0.1524)
				(type default)
			)
			(layer "F.SilkS")
		)
		(fp_rect
			(start -0.508 0.9398)
			(end 0.508 -0.9398)
			(stroke
				(width 0)
				(type default)
			)
			(fill no)
			(layer "F.CrtYd")
		)
		(fp_rect
			(start -0.508 0.9398)
			(end 0.508 -0.9398)
			(stroke
				(width 0)
				(type default)
			)
			(fill no)
			(layer "F.Fab")
		)
		(pad "1" smd custom
			(at 0 -0.4445 180)
			(size 0.1397 0.1397)
			(layers "F.Cu" "F.Mask" "F.Paste")
			(net "P12V_B")
			(options
				(clearance outline)
				(anchor circle)
			)
			(primitives
				(gr_poly
					(pts
						(arc
							(start -0.1778 -0.2794)
							(mid -0.249642 -0.249642)
							(end -0.2794 -0.1778)
						)
						(arc
							(start -0.2794 0.1778)
							(mid -0.249642 0.249642)
							(end -0.1778 0.2794)
						)
						(arc
							(start 0.1778 0.2794)
							(mid 0.249642 0.249642)
							(end 0.2794 0.1778)
						)
						(arc
							(start 0.2794 -0.1778)
							(mid 0.249642 -0.249642)
							(end 0.1778 -0.2794)
						)
					)
					(width 0)
					(fill yes)
				)
			)
		)
		(pad "2" smd custom
			(at 0 0.4445 180)
			(size 0.1397 0.1397)
			(layers "F.Cu" "F.Mask" "F.Paste")
			(net "SW_HDD_R8")
			(options
				(clearance outline)
				(anchor circle)
			)
			(primitives
				(gr_poly
					(pts
						(arc
							(start -0.1778 -0.2794)
							(mid -0.249642 -0.249642)
							(end -0.2794 -0.1778)
						)
						(arc
							(start -0.2794 0.1778)
							(mid -0.249642 0.249642)
							(end -0.1778 0.2794)
						)
						(arc
							(start 0.1778 0.2794)
							(mid 0.249642 0.249642)
							(end 0.2794 0.1778)
						)
						(arc
							(start 0.2794 -0.1778)
							(mid 0.249642 -0.249642)
							(end 0.1778 -0.2794)
						)
					)
					(width 0)
					(fill yes)
				)
			)
		)
	)
)
